# T6G (Grand Teton) — schematic netlist excerpt (pin names and nets, part order shuffled) for the footprints in the layout excerpt that follows; sources: Cadence DE-HDL packaged netlist, KiCad conversion of 04192023_DAF0TMB3IC0_F0TG_MB_C_brd_V02_OCP.brd

PC6  Q_CAP  0.1UF 25V 10% X7R  pkg 0402  page 210 : A = PVDDCR_CPU0_P1_VINSEN ; B = GND
PC470  Q_CAP  10UF 6.3V 20% X6S  pkg C0402  page 193 : A = PVDDCR_CPU0_P0_VCCS ; B = GND

(kicad_pcb
	(version 20260206)
	(generator "pcbnew")
	(generator_version "10.0")
	(general
		(thickness 1.6)
		(legacy_teardrops no)
	)
	(paper "A4")
	(title_block
		(title "04192023_DAF0TMB3IC0_F0TG_MB_C_brd_V02_OCP.brd")
		(comment 1 "Grand Teton / footprints 5864-5865 of 8354")
	)
	(layers
		(0 "F.Cu" signal "TOP")
		(4 "In1.Cu" signal "GND")
		(6 "In2.Cu" signal "IN1")
		(8 "In3.Cu" signal "GND1")
		(10 "In4.Cu" signal "IN2")
		(12 "In5.Cu" signal "GND2")
		(14 "In6.Cu" signal "IN3")
		(16 "In7.Cu" signal "GND3")
		(18 "In8.Cu" signal "VCC")
		(20 "In9.Cu" signal "VCC1")
		(22 "In10.Cu" signal "GND4")
		(24 "In11.Cu" signal "IN4")
		(26 "In12.Cu" signal "GND5")
		(28 "In13.Cu" signal "IN5")
		(30 "In14.Cu" signal "GND6")
		(32 "In15.Cu" signal "IN6")
		(34 "In16.Cu" signal "GND7")
		(2 "B.Cu" signal "BOTTOM")
		(9 "F.Adhes" user "F.Adhesive")
		(11 "B.Adhes" user "B.Adhesive")
		(13 "F.Paste" user "Package Geometry/Pastemask Top")
		(15 "B.Paste" user "Package Geometry/Pastemask Bottom")
		(5 "F.SilkS" user "Ref Des/Silkscreen Top")
		(7 "B.SilkS" user "Ref Des/Silkscreen Bottom")
		(1 "F.Mask" user "Board Geometry/Soldermask Top")
		(3 "B.Mask" user "Board Geometry/Soldermask Bottom")
		(17 "Dwgs.User" user "User.Drawings")
		(19 "Cmts.User" user "User.Comments")
		(21 "Eco1.User" user "User.Eco1")
		(23 "Eco2.User" user "User.Eco2")
		(25 "Edge.Cuts" user "Board Geometry/Outline")
		(27 "Margin" user)
		(31 "F.CrtYd" user "Package Geometry/Place Bound Top")
		(29 "B.CrtYd" user "Package Geometry/Place Bound Bottom")
		(35 "F.Fab" user "Ref Des/Assembly Top")
		(33 "B.Fab" user "Ref Des/Assembly Bottom")
	)
	(footprint ""
		(layer "B.Cu")
		(at 101.385878 -141.58341 180)
		(property "Reference" "PC6"
			(at 0 0 0)
			(layer "B.SilkS")
			(hide yes)
			(effects
				(font
					(size 1.27 1.27)
				)
				(justify mirror)
			)
		)
		(property "Value" ""
			(at 0 0 0)
			(layer "B.Fab")
			(effects
				(font
					(size 1.27 1.27)
				)
				(justify mirror)
			)
		)
		(duplicate_pad_numbers_are_jumpers no)
		(fp_line
			(start 0.7874 0.4064)
			(end 0.7874 -0.4064)
			(stroke
				(width 0.1524)
				(type default)
			)
			(layer "B.SilkS")
		)
		(fp_line
			(start 0.7874 -0.4064)
			(end -0.7874 -0.4064)
			(stroke
				(width 0.1524)
				(type default)
			)
			(layer "B.SilkS")
		)
		(fp_line
			(start -0.7874 0.4064)
			(end 0.7874 0.4064)
			(stroke
				(width 0.1524)
				(type default)
			)
			(layer "B.SilkS")
		)
		(fp_line
			(start -0.7874 -0.4064)
			(end -0.7874 0.4064)
			(stroke
				(width 0.1524)
				(type default)
			)
			(layer "B.SilkS")
		)
		(fp_line
			(start 0.67945 0.3048)
			(end 0.67945 -0.305054)
			(stroke
				(width 0.1)
				(type default)
			)
			(layer "B.Fab")
		)
		(fp_line
			(start 0.67945 -0.305054)
			(end 0.12065 -0.305054)
			(stroke
				(width 0.1)
				(type default)
			)
			(layer "B.Fab")
		)
		(fp_line
			(start 0.12065 0.3048)
			(end 0.67945 0.3048)
			(stroke
				(width 0.1)
				(type default)
			)
			(layer "B.Fab")
		)
		(fp_line
			(start 0.12065 0.2794)
			(end 0.12065 0.3048)
			(stroke
				(width 0.1)
				(type default)
			)
			(layer "B.Fab")
		)
		(fp_line
			(start 0.12065 -0.2794)
			(end -0.12065 -0.2794)
			(stroke
				(width 0.1)
				(type default)
			)
			(layer "B.Fab")
		)
		(fp_line
			(start 0.12065 -0.305054)
			(end 0.12065 -0.2794)
			(stroke
				(width 0.1)
				(type default)
			)
			(layer "B.Fab")
		)
		(fp_line
			(start -0.120396 0.3048)
			(end -0.120396 0.2794)
			(stroke
				(width 0.1)
				(type default)
			)
			(layer "B.Fab")
		)
		(fp_line
			(start -0.120396 0.2794)
			(end 0.12065 0.2794)
			(stroke
				(width 0.1)
				(type default)
			)
			(layer "B.Fab")
		)
		(fp_line
			(start -0.12065 -0.2794)
			(end -0.12065 -0.3048)
			(stroke
				(width 0.1)
				(type default)
			)
			(layer "B.Fab")
		)
		(fp_line
			(start -0.12065 -0.3048)
			(end -0.67945 -0.3048)
			(stroke
				(width 0.1)
				(type default)
			)
			(layer "B.Fab")
		)
		(fp_line
			(start -0.67945 0.3048)
			(end -0.120396 0.3048)
			(stroke
				(width 0.1)
				(type default)
			)
			(layer "B.Fab")
		)
		(fp_line
			(start -0.67945 -0.3048)
			(end -0.67945 0.3048)
			(stroke
				(width 0.1)
				(type default)
			)
			(layer "B.Fab")
		)
		(pad "1" smd circle
			(at 0.40005 0)
			(size 0 0)
			(layers "B.Cu" "B.Mask" "B.Paste")
			(net "PVDDCR_CPU0_P1_VINSEN")
		)
		(pad "2" smd circle
			(at -0.40005 0)
			(size 0 0)
			(layers "B.Cu" "B.Mask" "B.Paste")
			(net "GND")
		)
	)
	(footprint ""
		(layer "B.Cu")
		(at 382.208278 -137.535158 90)
		(property "Reference" "PC470"
			(at 0 0 90)
			(layer "B.SilkS")
			(hide yes)
			(effects
				(font
					(size 1.27 1.27)
				)
				(justify mirror)
			)
		)
		(property "Value" ""
			(at 0 0 90)
			(layer "B.Fab")
			(effects
				(font
					(size 1.27 1.27)
				)
				(justify mirror)
			)
		)
		(duplicate_pad_numbers_are_jumpers no)
		(fp_line
			(start 0.7874 -0.4064)
			(end -0.7874 -0.4064)
			(stroke
				(width 0.1524)
				(type default)
			)
			(layer "B.SilkS")
		)
		(fp_line
			(start -0.7874 -0.4064)
			(end -0.7874 0.4064)
			(stroke
				(width 0.1524)
				(type default)
			)
			(layer "B.SilkS")
		)
		(fp_line
			(start 0.7874 0.4064)
			(end 0.7874 -0.4064)
			(stroke
				(width 0.1524)
				(type default)
			)
			(layer "B.SilkS")
		)
		(fp_line
			(start -0.7874 0.4064)
			(end 0.7874 0.4064)
			(stroke
				(width 0.1524)
				(type default)
			)
			(layer "B.SilkS")
		)
		(fp_line
			(start 0.67945 -0.305054)
			(end 0.12065 -0.305054)
			(stroke
				(width 0.1)
				(type default)
			)
			(layer "B.Fab")
		)
		(fp_line
			(start 0.12065 -0.305054)
			(end 0.12065 -0.2794)
			(stroke
				(width 0.1)
				(type default)
			)
			(layer "B.Fab")
		)
		(fp_line
			(start -0.12065 -0.3048)
			(end -0.67945 -0.3048)
			(stroke
				(width 0.1)
				(type default)
			)
			(layer "B.Fab")
		)
		(fp_line
			(start -0.67945 -0.3048)
			(end -0.67945 0.3048)
			(stroke
				(width 0.1)
				(type default)
			)
			(layer "B.Fab")
		)
		(fp_line
			(start 0.12065 -0.2794)
			(end -0.12065 -0.2794)
			(stroke
				(width 0.1)
				(type default)
			)
			(layer "B.Fab")
		)
		(fp_line
			(start -0.12065 -0.2794)
			(end -0.12065 -0.3048)
			(stroke
				(width 0.1)
				(type default)
			)
			(layer "B.Fab")
		)
		(fp_line
			(start 0.12065 0.2794)
			(end 0.12065 0.3048)
			(stroke
				(width 0.1)
				(type default)
			)
			(layer "B.Fab")
		)
		(fp_line
			(start -0.120396 0.2794)
			(end 0.12065 0.2794)
			(stroke
				(width 0.1)
				(type default)
			)
			(layer "B.Fab")
		)
		(fp_line
			(start 0.67945 0.3048)
			(end 0.67945 -0.305054)
			(stroke
				(width 0.1)
				(type default)
			)
			(layer "B.Fab")
		)
		(fp_line
			(start 0.12065 0.3048)
			(end 0.67945 0.3048)
			(stroke
				(width 0.1)
				(type default)
			)
			(layer "B.Fab")
		)
		(fp_line
			(start -0.120396 0.3048)
			(end -0.120396 0.2794)
			(stroke
				(width 0.1)
				(type default)
			)
			(layer "B.Fab")
		)
		(fp_line
			(start -0.67945 0.3048)
			(end -0.120396 0.3048)
			(stroke
				(width 0.1)
				(type default)
			)
			(layer "B.Fab")
		)
		(pad "1" smd circle
			(at 0.40005 0 270)
			(size 0 0)
			(layers "B.Cu" "B.Mask" "B.Paste")
			(net "PVDDCR_CPU0_P0_VCCS")
		)
		(pad "2" smd circle
			(at -0.40005 0 270)
			(size 0 0)
			(layers "B.Cu" "B.Mask" "B.Paste")
			(net "GND")
		)
	)
)
